FILE_TYPE = CONNECTIVITY;
{Allegro Design Entry HDL 17.2-2016 S081 (4005846) 1/11/2022}
"PAGE_NUMBER" = 13;
0"NC";
1"I3C_SPD_DDRABCD_CPU0_SCL";
2"PU_CPU0_SOCKET_ID1";
3"PU_CPU0_SOCKET_ID0";
4"PU_CPU0_FRMAGENT";
5"PD_CPU0_DMIMODE_OVERRIDE";
6"CLK_25M_NSSC_CPU0_DP";
7"PD_CPU0_TXT_PLTEN";
8"PU_CPU0_TXT_AGENT";
9"JTAG_DBP_CPU0_QS_GTL_R_TMS";
10"JTAG_CPU0_MUX_GTL_TDO";
11"JTAG_DBP_CPU0_GTL_R_TDI";
12"JTAG_DBP_CPU0_GTL_R_TCK";
13"PU_CPU0_SOCKET_ID2";
14"PU_CPU0_SAFE_MODE_BOOT";
15"NC_CLK_PFT_OUT_CPU0_DN";
16"NC_CLK_PFT_OUT_CPU0_DP";
17"PD_EXT_CLK_SEL_CPU0";
18"NC_XTAL_CPU0_25M_IN";
19"PUD_XTAL_CPU0_MODE1";
20"FM_CPU0_PROC_ID0";
21"FM_CPU0_PROC_ID1";
22"TP_CPU0_PROCDIS_COD_GTL_N";
23"H_CPU0_PREQ_QS_GTL_R_N";
24"H_CPU0_PRDY_QS_GTL_R_N";
25"FM_CPU0_PKGID0";
26"FM_CPU0_PKGID1";
27"FM_CPU0_PKGID2";
28"PECI_CPU0_GTL_R";
29"TP_CPU0_BR23";
30"PU_CPU0_LEGACY_SKT";
31"RST_CPU0_DRAM_GH_N";
32"RST_CPU0_DRAM_EF_N";
33"I3C_SPD_DDREFGH_CPU0_SDA";
34"I3C_SPD_DDREFGH_CPU0_SCL";
35"RST_CPU0_DRAM_CD_N";
36"RST_CPU0_DRAM_AB_N";
37"I3C_SPD_DDRABCD_CPU0_SDA";
38"H_CPU0_BMCINIT_LVC1";
39"PD_CPU0_BIST_ENABLE";
40"CLK_100M_DB2000_CPU0_BCLK3_DP";
41"CLK_100M_DB2000_CPU0_BCLK3_DN";
42"CLK_100M_DB2000_CPU0_BCLK2_DP";
43"CLK_100M_DB2000_CPU0_BCLK2_DN";
44"CLK_100M_DB2000_CPU0_BCLK0_DP";
45"CLK_100M_DB2000_CPU0_BCLK1_DN";
46"CLK_100M_DB2000_CPU0_BCLK1_DP";
47"CLK_100M_DB2000_CPU0_BCLK0_DN";
48"PUD_XTAL_CPU0_MODE0";
49"NC_XTAL_CPU0_25M_OUT";
50"CLK_25M_NSSC_CPU0_DN";
51"PECI_CPU_GTL";
52"JTAG_MUX_CPU0_GTL_TDI";
53"H_CPU_PRDY_QS_GTL_N";
54"H_CPU_PREQ_QS_GTL_N";
55"JTAG_DBP_CPU_QS_GTL_TMS";
56"JTAG_DBP_CPU_GTL_TCK";
%"Q_RES"
"1","(-2125,2025)","0","pure_quanta","I16";
;
PART_NUMBER"CS11002FB07"
MATERIAL"CHIP"
WATTAGE"1/16W"
TOLERANCE"1%"
PACK_TYPE"0402LF"
VALUE"100"
$LOCATION"R2"
CDS_LIB"pure_quanta"
$LOCATION"R2"
CDS_LOCATION"R2"
$SEC"1"
CDS_SEC"1";
"B"
$PN"2"23;
"A"
$PN"1"54;
%"Q_RES"
"1","(-2125,2075)","0","pure_quanta","I18";
;
PART_NUMBER"CS01002FB07"
WATTAGE"1/16W"
TOLERANCE"1%"
VALUE"10"
MATERIAL"CHIP"
PACK_TYPE"0402LF"
$LOCATION"R1"
CDS_LIB"pure_quanta"
$LOCATION"R1"
CDS_LOCATION"R1"
$SEC"1"
CDS_SEC"1";
"B"
$PN"2"24;
"A"
$PN"1"53;
%"Q_RES"
"1","(-2125,1925)","0","pure_quanta","I21";
;
PART_NUMBER"CS03322FB03"
PACK_TYPE"0402LF"
WATTAGE"1/16W"
TOLERANCE"1%"
MATERIAL"CHIP"
VALUE"33.2"
$LOCATION"R3"
CDS_LIB"pure_quanta"
$LOCATION"R3"
CDS_LOCATION"R3"
$SEC"1"
CDS_SEC"1";
"B"
$PN"2"28;
"A"
$PN"1"51;
%"Q_RES"
"1","(-2125,1775)","0","pure_quanta","I24";
;
PART_NUMBER"CS11002FB07"
PACK_TYPE"0402LF"
TOLERANCE"1%"
VALUE"100"
$LOCATION"R5"
CDS_LIB"pure_quanta"
MATERIAL"CHIP"
WATTAGE"1/16W"
$LOCATION"R5"
CDS_LOCATION"R5"
$SEC"1"
CDS_SEC"1";
"B"
$PN"2"12;
"A"
$PN"1"56;
%"Q_RES"
"1","(-2125,1725)","0","pure_quanta","I25";
;
PART_NUMBER"CS11002FB07"
MATERIAL"CHIP"
WATTAGE"1/16W"
VALUE"100"
TOLERANCE"1%"
PACK_TYPE"0402LF"
$LOCATION"R6"
CDS_LIB"pure_quanta"
$LOCATION"R6"
CDS_LOCATION"R6"
$SEC"1"
CDS_SEC"1";
"B"
$PN"2"9;
"A"
$PN"1"55;
%"Q_RES"
"1","(-2125,1825)","0","pure_quanta","I29";
;
PART_NUMBER"CS12002FB06"
PACK_TYPE"0402LF"
TOLERANCE"1%"
VALUE"200"
WATTAGE"1/16W"
MATERIAL"CHIP"
$LOCATION"R4"
CDS_LIB"pure_quanta"
$LOCATION"R4"
CDS_LOCATION"R4"
$SEC"1"
CDS_SEC"1";
"B"
$PN"2"11;
"A"
$PN"1"52;
%"SOCKET4677_AZIF0045P001C01CS"
"1","(700,2650)","0","pure_quanta","I57";
;
PART_NUMBER"DGA^7000023"
PART_TYPE"SMLF"
MATERIAL"IO"
VALUE"SOCKET4677_AZIF0045-P001C01CS"
$LOCATION"U2"
CDS_LIB"pure_quanta"
NEEDS_NO_SIZE"TRUE"
CDS_LMAN_SYM_OUTLINE"-1100,1100,1050,-1050"
CDS_LOCATION"U2"
$SEC"1"
CDS_SEC"1";
"XTAL_CLK_DN \B"
$PN"CW31"50;
"RSVD157"
$PN"D4"49;
"RSVD120"
$PN"CL72"48;
"BCLK0_DN \B"
$PN"AT30"47;
"BCLK1_DP"
$PN"CW29"46;
"BCLK1_DN \B"
$PN"CY28"45;
"BCLK0_DP"
$PN"AV30"44;
"BCLK2_DN \B"
$PN"AU29"43;
"BCLK2_DP"
$PN"AV28"42;
"BCLK3_DN \B"
$PN"CW27"41;
"BCLK3_DP"
$PN"DA27"40;
"BIST_ENABLE"
$PN"AT18"39;
"BMCINIT"
$PN"BN23"38;
"DDR0123_SPDSCL"
$PN"BT22"1;
"DDR0123_SPDSDA"
$PN"BY22"37;
"DDR01_RESET_N \B"
$PN"AU50"36;
"DDR23_RESET_N \B"
$PN"AV51"35;
"DDR4567_SPDSCL"
$PN"CU17"34;
"DDR4567_SPDSDA"
$PN"CT18"33;
"DDR45_RESET_N \B"
$PN"CY42"32;
"DDR67_RESET_N \B"
$PN"CY55"31;
"DMIMODE_OVERRIDE"
$PN"AW17"5;
"FRMAGENT"
$PN"AU17"4;
"LEGACY_SKT"
$PN"CY59"30;
"RSVD72"
$PN"BR23"29;
"PECI"
$PN"BH24"28;
"PKG_ID2"
$PN"BN64"27;
"PKG_ID1"
$PN"AY63"26;
"PKG_ID0"
$PN"BL64"25;
"PRDY_N \B"
$PN"BP26"24;
"PREQ_N \B"
$PN"AV22"23;
"PROCDIS_N \B"
$PN"DA52"22;
"PROC_ID1"
$PN"BH71"21;
"PROC_ID0"
$PN"BG72"20;
"RSVD108"
$PN"CJ72"19;
"RSVD161"
$PN"G5"18;
"RSVD76"
$PN"BY24"17;
"RSVD88"
$PN"CD71"16;
"RSVD91"
$PN"CE70"15;
"SAFE_MODE_BOOT"
$PN"AU23"14;
"SOCKET_ID2"
$PN"CT61"13;
"SOCKET_ID1"
$PN"CY61"2;
"SOCKET_ID0"
$PN"CW60"3;
"TCK"
$PN"BT24"12;
"TDI"
$PN"BV24"11;
"TDO"
$PN"BW25"10;
"TMS"
$PN"BR25"9;
"TXT_AGENT"
$PN"BT26"8;
"TXT_PLTEN"
$PN"CT20"7;
"XTAL_CLK_DP"
$PN"CY32"6;
END.
